# T6G (Grand Teton) — schematic netlist excerpt (pin names and nets, part order shuffled) for the footprints in the layout excerpt that follows; sources: Cadence DE-HDL packaged netlist, KiCad conversion of 04192023_DAF0TMB3IC0_F0TG_MB_C_brd_V02_OCP.brd

R1699  Q_RES  10 1% CHIP  pkg 0402LF  page 101 : A = I3C_SPD_DDRAF_CPU1_SDA ; B = I3C_SPD_DDRD_CPU1_SDA
R1198  Q_RES  0 5% CHIP  pkg 0201LF  page 186 : A = RST_SMB_RT_ROM_R1_N ; B = FM_SMB_RT_ROM_MUX3_SEL
R3785  Q_RES  0 5% CHIP  pkg 0402LF  page 134 : A = P3V3_OCP_UV_1_R1 ; B = P3V3_OCP_UV_1

(kicad_pcb
	(version 20260206)
	(generator "pcbnew")
	(generator_version "10.0")
	(general
		(thickness 1.6)
		(legacy_teardrops no)
	)
	(paper "A4")
	(title_block
		(title "04192023_DAF0TMB3IC0_F0TG_MB_C_brd_V02_OCP.brd")
		(comment 1 "Grand Teton / footprints 5844-5846 of 8354")
	)
	(layers
		(0 "F.Cu" signal "TOP")
		(4 "In1.Cu" signal "GND")
		(6 "In2.Cu" signal "IN1")
		(8 "In3.Cu" signal "GND1")
		(10 "In4.Cu" signal "IN2")
		(12 "In5.Cu" signal "GND2")
		(14 "In6.Cu" signal "IN3")
		(16 "In7.Cu" signal "GND3")
		(18 "In8.Cu" signal "VCC")
		(20 "In9.Cu" signal "VCC1")
		(22 "In10.Cu" signal "GND4")
		(24 "In11.Cu" signal "IN4")
		(26 "In12.Cu" signal "GND5")
		(28 "In13.Cu" signal "IN5")
		(30 "In14.Cu" signal "GND6")
		(32 "In15.Cu" signal "IN6")
		(34 "In16.Cu" signal "GND7")
		(2 "B.Cu" signal "BOTTOM")
		(9 "F.Adhes" user "F.Adhesive")
		(11 "B.Adhes" user "B.Adhesive")
		(13 "F.Paste" user "Package Geometry/Pastemask Top")
		(15 "B.Paste" user "Package Geometry/Pastemask Bottom")
		(5 "F.SilkS" user "Ref Des/Silkscreen Top")
		(7 "B.SilkS" user "Ref Des/Silkscreen Bottom")
		(1 "F.Mask" user "Board Geometry/Soldermask Top")
		(3 "B.Mask" user "Board Geometry/Soldermask Bottom")
		(17 "Dwgs.User" user "User.Drawings")
		(19 "Cmts.User" user "User.Comments")
		(21 "Eco1.User" user "User.Eco1")
		(23 "Eco2.User" user "User.Eco2")
		(25 "Edge.Cuts" user "Board Geometry/Outline")
		(27 "Margin" user)
		(31 "F.CrtYd" user "Package Geometry/Place Bound Top")
		(29 "B.CrtYd" user "Package Geometry/Place Bound Bottom")
		(35 "F.Fab" user "Ref Des/Assembly Top")
		(33 "B.Fab" user "Ref Des/Assembly Bottom")
	)
	(footprint ""
		(layer "B.Cu")
		(at 429.40224 -108.867448 90)
		(property "Reference" "R3785"
			(at 0 0 90)
			(layer "B.SilkS")
			(hide yes)
			(effects
				(font
					(size 1.27 1.27)
				)
				(justify mirror)
			)
		)
		(property "Value" ""
			(at 0 0 90)
			(layer "B.Fab")
			(effects
				(font
					(size 1.27 1.27)
				)
				(justify mirror)
			)
		)
		(duplicate_pad_numbers_are_jumpers no)
		(fp_line
			(start 0.7874 -0.4064)
			(end -0.7874 -0.4064)
			(stroke
				(width 0.1524)
				(type default)
			)
			(layer "B.SilkS")
		)
		(fp_line
			(start -0.7874 -0.4064)
			(end -0.7874 0.4064)
			(stroke
				(width 0.1524)
				(type default)
			)
			(layer "B.SilkS")
		)
		(fp_line
			(start 0.7874 0.4064)
			(end 0.7874 -0.4064)
			(stroke
				(width 0.1524)
				(type default)
			)
			(layer "B.SilkS")
		)
		(fp_line
			(start -0.7874 0.4064)
			(end 0.7874 0.4064)
			(stroke
				(width 0.1524)
				(type default)
			)
			(layer "B.SilkS")
		)
		(fp_line
			(start 0.67945 -0.305054)
			(end 0.12065 -0.305054)
			(stroke
				(width 0.1)
				(type default)
			)
			(layer "B.Fab")
		)
		(fp_line
			(start 0.12065 -0.305054)
			(end 0.12065 -0.2794)
			(stroke
				(width 0.1)
				(type default)
			)
			(layer "B.Fab")
		)
		(fp_line
			(start -0.12065 -0.3048)
			(end -0.67945 -0.3048)
			(stroke
				(width 0.1)
				(type default)
			)
			(layer "B.Fab")
		)
		(fp_line
			(start -0.67945 -0.3048)
			(end -0.67945 0.3048)
			(stroke
				(width 0.1)
				(type default)
			)
			(layer "B.Fab")
		)
		(fp_line
			(start 0.12065 -0.2794)
			(end -0.12065 -0.2794)
			(stroke
				(width 0.1)
				(type default)
			)
			(layer "B.Fab")
		)
		(fp_line
			(start -0.12065 -0.2794)
			(end -0.12065 -0.3048)
			(stroke
				(width 0.1)
				(type default)
			)
			(layer "B.Fab")
		)
		(fp_line
			(start 0.12065 0.2794)
			(end 0.12065 0.3048)
			(stroke
				(width 0.1)
				(type default)
			)
			(layer "B.Fab")
		)
		(fp_line
			(start -0.120396 0.2794)
			(end 0.12065 0.2794)
			(stroke
				(width 0.1)
				(type default)
			)
			(layer "B.Fab")
		)
		(fp_line
			(start 0.67945 0.3048)
			(end 0.67945 -0.305054)
			(stroke
				(width 0.1)
				(type default)
			)
			(layer "B.Fab")
		)
		(fp_line
			(start 0.12065 0.3048)
			(end 0.67945 0.3048)
			(stroke
				(width 0.1)
				(type default)
			)
			(layer "B.Fab")
		)
		(fp_line
			(start -0.120396 0.3048)
			(end -0.120396 0.2794)
			(stroke
				(width 0.1)
				(type default)
			)
			(layer "B.Fab")
		)
		(fp_line
			(start -0.67945 0.3048)
			(end -0.120396 0.3048)
			(stroke
				(width 0.1)
				(type default)
			)
			(layer "B.Fab")
		)
		(pad "1" smd circle
			(at 0.40005 0 270)
			(size 0 0)
			(layers "B.Cu" "B.Mask" "B.Paste")
			(net "P3V3_OCP_UV_1_R1")
		)
		(pad "2" smd circle
			(at -0.40005 0 270)
			(size 0 0)
			(layers "B.Cu" "B.Mask" "B.Paste")
			(net "P3V3_OCP_UV_1")
		)
	)
	(footprint ""
		(layer "B.Cu")
		(at 36.040568 -195.8848 180)
		(property "Reference" "R1699"
			(at 0 0 0)
			(layer "B.SilkS")
			(hide yes)
			(effects
				(font
					(size 1.27 1.27)
				)
				(justify mirror)
			)
		)
		(property "Value" ""
			(at 0 0 0)
			(layer "B.Fab")
			(effects
				(font
					(size 1.27 1.27)
				)
				(justify mirror)
			)
		)
		(duplicate_pad_numbers_are_jumpers no)
		(fp_line
			(start 0.7874 0.4064)
			(end 0.7874 -0.4064)
			(stroke
				(width 0.1524)
				(type default)
			)
			(layer "B.SilkS")
		)
		(fp_line
			(start 0.7874 -0.4064)
			(end -0.7874 -0.4064)
			(stroke
				(width 0.1524)
				(type default)
			)
			(layer "B.SilkS")
		)
		(fp_line
			(start -0.7874 0.4064)
			(end 0.7874 0.4064)
			(stroke
				(width 0.1524)
				(type default)
			)
			(layer "B.SilkS")
		)
		(fp_line
			(start -0.7874 -0.4064)
			(end -0.7874 0.4064)
			(stroke
				(width 0.1524)
				(type default)
			)
			(layer "B.SilkS")
		)
		(fp_line
			(start 0.67945 0.3048)
			(end 0.67945 -0.305054)
			(stroke
				(width 0.1)
				(type default)
			)
			(layer "B.Fab")
		)
		(fp_line
			(start 0.67945 -0.305054)
			(end 0.12065 -0.305054)
			(stroke
				(width 0.1)
				(type default)
			)
			(layer "B.Fab")
		)
		(fp_line
			(start 0.12065 0.3048)
			(end 0.67945 0.3048)
			(stroke
				(width 0.1)
				(type default)
			)
			(layer "B.Fab")
		)
		(fp_line
			(start 0.12065 0.2794)
			(end 0.12065 0.3048)
			(stroke
				(width 0.1)
				(type default)
			)
			(layer "B.Fab")
		)
		(fp_line
			(start 0.12065 -0.2794)
			(end -0.12065 -0.2794)
			(stroke
				(width 0.1)
				(type default)
			)
			(layer "B.Fab")
		)
		(fp_line
			(start 0.12065 -0.305054)
			(end 0.12065 -0.2794)
			(stroke
				(width 0.1)
				(type default)
			)
			(layer "B.Fab")
		)
		(fp_line
			(start -0.120396 0.3048)
			(end -0.120396 0.2794)
			(stroke
				(width 0.1)
				(type default)
			)
			(layer "B.Fab")
		)
		(fp_line
			(start -0.120396 0.2794)
			(end 0.12065 0.2794)
			(stroke
				(width 0.1)
				(type default)
			)
			(layer "B.Fab")
		)
		(fp_line
			(start -0.12065 -0.2794)
			(end -0.12065 -0.3048)
			(stroke
				(width 0.1)
				(type default)
			)
			(layer "B.Fab")
		)
		(fp_line
			(start -0.12065 -0.3048)
			(end -0.67945 -0.3048)
			(stroke
				(width 0.1)
				(type default)
			)
			(layer "B.Fab")
		)
		(fp_line
			(start -0.67945 0.3048)
			(end -0.120396 0.3048)
			(stroke
				(width 0.1)
				(type default)
			)
			(layer "B.Fab")
		)
		(fp_line
			(start -0.67945 -0.3048)
			(end -0.67945 0.3048)
			(stroke
				(width 0.1)
				(type default)
			)
			(layer "B.Fab")
		)
		(pad "1" smd circle
			(at 0.40005 0)
			(size 0 0)
			(layers "B.Cu" "B.Mask" "B.Paste")
			(net "I3C_SPD_DDRAF_CPU1_SDA")
		)
		(pad "2" smd circle
			(at -0.40005 0)
			(size 0 0)
			(layers "B.Cu" "B.Mask" "B.Paste")
			(net "I3C_SPD_DDRD_CPU1_SDA")
		)
	)
	(footprint ""
		(layer "B.Cu")
		(at 170.39082 -425.053506 -90)
		(property "Reference" "R1198"
			(at 0 0 90)
			(layer "B.SilkS")
			(hide yes)
			(effects
				(font
					(size 1.27 1.27)
				)
				(justify mirror)
			)
		)
		(property "Value" ""
			(at 0 0 90)
			(layer "B.Fab")
			(effects
				(font
					(size 1.27 1.27)
				)
				(justify mirror)
			)
		)
		(duplicate_pad_numbers_are_jumpers no)
		(fp_line
			(start -0.32512 0.175006)
			(end 0.32512 0.175006)
			(stroke
				(width 0.1)
				(type default)
			)
			(layer "B.Fab")
		)
		(fp_line
			(start 0.32512 0.175006)
			(end 0.32512 -0.175006)
			(stroke
				(width 0.1)
				(type default)
			)
			(layer "B.Fab")
		)
		(fp_line
			(start -0.32512 -0.175006)
			(end -0.32512 0.175006)
			(stroke
				(width 0.1)
				(type default)
			)
			(layer "B.Fab")
		)
		(fp_line
			(start 0.32512 -0.175006)
			(end -0.32512 -0.175006)
			(stroke
				(width 0.1)
				(type default)
			)
			(layer "B.Fab")
		)
		(pad "1" smd rect
			(at 0.2667 0 90)
			(size 0.3048 0.381)
			(layers "B.Cu" "B.Mask" "B.Paste")
			(net "RST_SMB_RT_ROM_R1_N")
		)
		(pad "2" smd rect
			(at -0.2667 0 270)
			(size 0.3048 0.381)
			(layers "B.Cu" "B.Mask" "B.Paste")
			(net "FM_SMB_RT_ROM_MUX3_SEL")
		)
	)
)
